(kicad_pcb
	(version 20260206)
	(generator "pcbnew")
	(generator_version "10.0")
	(general
		(thickness 1.6)
		(legacy_teardrops no)
	)
	(paper "A4")
	(title_block
		(title "04192023_DAF0TMB3IC0_F0TG_MB_C_brd_V02_OCP.brd")
		(comment 1 "Grand Teton / footprints 4249-4254 of 8354")
	)
	(layers
		(0 "F.Cu" signal "TOP")
		(4 "In1.Cu" signal "GND")
		(6 "In2.Cu" signal "IN1")
		(8 "In3.Cu" signal "GND1")
		(10 "In4.Cu" signal "IN2")
		(12 "In5.Cu" signal "GND2")
		(14 "In6.Cu" signal "IN3")
		(16 "In7.Cu" signal "GND3")
		(18 "In8.Cu" signal "VCC")
		(20 "In9.Cu" signal "VCC1")
		(22 "In10.Cu" signal "GND4")
		(24 "In11.Cu" signal "IN4")
		(26 "In12.Cu" signal "GND5")
		(28 "In13.Cu" signal "IN5")
		(30 "In14.Cu" signal "GND6")
		(32 "In15.Cu" signal "IN6")
		(34 "In16.Cu" signal "GND7")
		(2 "B.Cu" signal "BOTTOM")
		(9 "F.Adhes" user "F.Adhesive")
		(11 "B.Adhes" user "B.Adhesive")
		(13 "F.Paste" user "Package Geometry/Pastemask Top")
		(15 "B.Paste" user "Package Geometry/Pastemask Bottom")
		(5 "F.SilkS" user "Ref Des/Silkscreen Top")
		(7 "B.SilkS" user "Ref Des/Silkscreen Bottom")
		(1 "F.Mask" user "Board Geometry/Soldermask Top")
		(3 "B.Mask" user "Board Geometry/Soldermask Bottom")
		(17 "Dwgs.User" user "User.Drawings")
		(19 "Cmts.User" user "User.Comments")
		(21 "Eco1.User" user "User.Eco1")
		(23 "Eco2.User" user "User.Eco2")
		(25 "Edge.Cuts" user "Board Geometry/Outline")
		(27 "Margin" user)
		(31 "F.CrtYd" user "Package Geometry/Place Bound Top")
		(29 "B.CrtYd" user "Package Geometry/Place Bound Bottom")
		(35 "F.Fab" user "Ref Des/Assembly Top")
		(33 "B.Fab" user "Ref Des/Assembly Bottom")
	)
	(footprint ""
		(layer "F.Cu")
		(at 454.210674 -397.245332)
		(property "Reference" "PU6504"
			(at -2.411984 -7.177024 0)
			(unlocked yes)
			(layer "F.SilkS")
			(effects
				(font
					(size 0.7874 0.5842)
					(thickness 0.1524)
				)
				(justify left)
			)
		)
		(property "Value" ""
			(at 0 0 0)
			(layer "F.Fab")
			(effects
				(font
					(size 1.27 1.27)
				)
			)
		)
		(duplicate_pad_numbers_are_jumpers no)
		(fp_line
			(start -2.500122 -2.999994)
			(end -2.24409 -2.999994)
			(stroke
				(width 0.1524)
				(type default)
			)
			(layer "F.SilkS")
		)
		(fp_line
			(start -2.500122 -2.529078)
			(end -2.500122 -2.999994)
			(stroke
				(width 0.1524)
				(type default)
			)
			(layer "F.SilkS")
		)
		(fp_line
			(start -2.500122 0.6604)
			(end -2.500122 0.229108)
			(stroke
				(width 0.1524)
				(type default)
			)
			(layer "F.SilkS")
		)
		(fp_line
			(start -2.500122 2.999994)
			(end -2.500122 2.339594)
			(stroke
				(width 0.1524)
				(type default)
			)
			(layer "F.SilkS")
		)
		(fp_line
			(start -2.2987 2.999994)
			(end -2.500122 2.999994)
			(stroke
				(width 0.1524)
				(type default)
			)
			(layer "F.SilkS")
		)
		(fp_line
			(start 2.31394 -2.999994)
			(end 2.500122 -2.999994)
			(stroke
				(width 0.1524)
				(type default)
			)
			(layer "F.SilkS")
		)
		(fp_line
			(start 2.500122 -2.999994)
			(end 2.500122 -2.44348)
			(stroke
				(width 0.1524)
				(type default)
			)
			(layer "F.SilkS")
		)
		(fp_line
			(start 2.500122 2.339594)
			(end 2.500122 2.999994)
			(stroke
				(width 0.1524)
				(type default)
			)
			(layer "F.SilkS")
		)
		(fp_line
			(start 2.500122 2.999994)
			(end 2.2987 2.999994)
			(stroke
				(width 0.1524)
				(type default)
			)
			(layer "F.SilkS")
		)
		(fp_poly
			(pts
				(xy -3.10769 -3.61823) (xy -3.812794 -2.886964) (xy -2.728722 -2.54762)
			)
			(stroke
				(width 0)
				(type default)
			)
			(fill yes)
			(layer "F.SilkS")
		)
		(fp_line
			(start -2.500122 -2.999994)
			(end 2.500122 -2.999994)
			(stroke
				(width 0.1)
				(type default)
			)
			(layer "F.Fab")
		)
		(fp_line
			(start -2.500122 2.999994)
			(end -2.500122 -2.999994)
			(stroke
				(width 0.1)
				(type default)
			)
			(layer "F.Fab")
		)
		(fp_line
			(start 2.500122 -2.999994)
			(end 2.500122 2.999994)
			(stroke
				(width 0.1)
				(type default)
			)
			(layer "F.Fab")
		)
		(fp_line
			(start 2.500122 2.999994)
			(end -2.500122 2.999994)
			(stroke
				(width 0.1)
				(type default)
			)
			(layer "F.Fab")
		)
		(fp_poly
			(pts
				(xy -4.218432 -2.783078) (xy -4.218432 -1.767078) (xy -3.202432 -2.275078)
			)
			(stroke
				(width 0)
				(type default)
			)
			(fill yes)
			(layer "F.Fab")
		)
		(pad "1" smd rect
			(at -2.400046 -2.275078 90)
			(size 0.2286 0.6096)
			(layers "F.Cu" "F.Mask" "F.Paste")
			(net "P0V9_RETIMER_CPU0_VOS2")
		)
		(pad "2" smd rect
			(at -2.400046 -1.82499 90)
			(size 0.2286 0.6096)
			(layers "F.Cu" "F.Mask" "F.Paste")
			(net "GND")
		)
		(pad "3" smd rect
			(at -2.400046 -1.374902 90)
			(size 0.2286 0.6096)
			(layers "F.Cu" "F.Mask" "F.Paste")
			(net "P0V9_RETIMER_CPU0_VCC2")
		)
		(pad "4" smd rect
			(at -2.400046 -0.925068 90)
			(size 0.2286 0.6096)
			(layers "F.Cu" "F.Mask" "F.Paste")
			(net "P0V9_RETIMER_CPU0_PVCC")
		)
		(pad "5" smd rect
			(at -2.400046 -0.47498 90)
			(size 0.2286 0.6096)
			(layers "F.Cu" "F.Mask" "F.Paste")
			(net "GND")
		)
		(pad "6" smd rect
			(at -2.400046 -0.024892 90)
			(size 0.2286 0.6096)
			(layers "F.Cu" "F.Mask" "F.Paste")
			(net "NC_PV09_RETIMER_CPU0_GL1_2")
		)
		(pad "7_9-20_24" smd circle
			(at 0 1.150112 90)
			(size 0 0)
			(layers "F.Cu" "F.Mask" "F.Paste")
			(net "GND")
		)
		(pad "10_19" smd rect
			(at 0 2.899918 90)
			(size 0.6096 4.318)
			(layers "F.Cu" "F.Mask" "F.Paste")
			(net "SW_P0V9_RETIMER_CPU0_SW2")
		)
		(pad "25_29" smd rect
			(at 1.549908 -1.279906 270)
			(size 2.0574 2.3114)
			(layers "F.Cu" "F.Mask" "F.Paste")
			(net "SW_P12V_AUX_P0V9_RETIMER_CPU0_FLT")
		)
		(pad "30" smd rect
			(at 2.05994 -2.899918)
			(size 0.2286 0.6096)
			(layers "F.Cu" "F.Mask" "F.Paste")
			(net "SW_P12V_AUX_P0V9_RETIMER_CPU0_FLT")
		)
		(pad "31" smd rect
			(at 1.610106 -2.899918)
			(size 0.2286 0.6096)
			(layers "F.Cu" "F.Mask" "F.Paste")
			(net "NC_PV09_RETIMER_CPU0_DNC2")
		)
		(pad "32" smd rect
			(at 1.160018 -2.899918)
			(size 0.2286 0.6096)
			(layers "F.Cu" "F.Mask" "F.Paste")
			(net "SW_P0V9_RETIMER_CPU0_PH2")
		)
		(pad "33" smd rect
			(at 0.70993 -2.899918)
			(size 0.2286 0.6096)
			(layers "F.Cu" "F.Mask" "F.Paste")
			(net "SW_P0V9_RETIMER_CPU0_BOOT2")
		)
		(pad "34" smd rect
			(at 0.260096 -2.899918)
			(size 0.2286 0.6096)
			(layers "F.Cu" "F.Mask" "F.Paste")
			(net "P0V9_RETIMER_CPU0_PWM2")
		)
		(pad "35" smd rect
			(at -0.189992 -2.899918)
			(size 0.2286 0.6096)
			(layers "F.Cu" "F.Mask" "F.Paste")
			(net "P0V9_RETIMER_CPU0_VCC2")
		)
		(pad "36" smd rect
			(at -0.64008 -2.899918)
			(size 0.2286 0.6096)
			(layers "F.Cu" "F.Mask" "F.Paste")
			(net "P0V9_RETIMER_CPU0_TEMP0")
		)
		(pad "37" smd rect
			(at -1.089914 -2.899918)
			(size 0.2286 0.6096)
			(layers "F.Cu" "F.Mask" "F.Paste")
			(net "P0V9_RETIMER_CPU0_LSET2")
		)
		(pad "38" smd rect
			(at -1.540002 -2.899918)
			(size 0.2286 0.6096)
			(layers "F.Cu" "F.Mask" "F.Paste")
			(net "P0V9_RETIMER_CPU0_IMON2")
		)
		(pad "39" smd rect
			(at -1.99009 -2.899918)
			(size 0.2286 0.6096)
			(layers "F.Cu" "F.Mask" "F.Paste")
			(net "PV09_RETIMER_CPU0_VCCS")
		)
		(pad "40" smd rect
			(at -0.87503 -1.27508)
			(size 1.7526 1.9558)
			(layers "F.Cu" "F.Mask" "F.Paste")
			(net "GND")
		)
		(pad "41" smd rect
			(at -1.525016 0.249936 270)
			(size 0.3048 0.4572)
			(layers "F.Cu" "F.Mask" "F.Paste")
			(net "NC_PV09_RETIMER_CPU0_GL2_2")
		)
		(zone
			(layer "F.Cu")
			(hatch none 0.5)
			(connect_pads
				(clearance 0)
			)
			(min_thickness 0.25)
			(keepout
				(tracks not_allowed)
				(vias allowed)
				(pads allowed)
				(copperpour not_allowed)
				(footprints allowed)
			)
			(placement
				(enabled no)
				(sheetname "")
			)
			(fill
				(thermal_gap 0.5)
				(thermal_bridge_width 0.5)
				(island_removal_mode 0)
			)
			(polygon
				(pts
					(xy 451.710552 -394.245338) (xy 451.710552 -394.994638) (xy 456.710796 -394.994638) (xy 456.710796 -394.245338)
					(xy 456.420474 -394.245338) (xy 456.420474 -394.701014) (xy 452.000874 -394.701014) (xy 452.000874 -394.245338)
				)
			)
		)
		(zone
			(layer "F.Cu")
			(hatch none 0.5)
			(connect_pads
				(clearance 0)
			)
			(min_thickness 0.25)
			(keepout
				(tracks not_allowed)
				(vias allowed)
				(pads allowed)
				(copperpour not_allowed)
				(footprints allowed)
			)
			(placement
				(enabled no)
				(sheetname "")
			)
			(fill
				(thermal_gap 0.5)
				(thermal_bridge_width 0.5)
				(island_removal_mode 0)
			)
			(polygon
				(pts
					(xy 451.710552 -396.496032) (xy 451.710552 -396.952724) (xy 452.406258 -396.952724) (xy 452.406258 -396.792196)
					(xy 452.965058 -396.792196) (xy 452.965058 -397.198596) (xy 452.406258 -397.198596) (xy 452.406258 -396.978124)
					(xy 451.710552 -396.978124) (xy 451.710552 -397.105124) (xy 452.166228 -397.105124) (xy 452.166228 -399.282666)
					(xy 452.408544 -399.282666) (xy 452.408544 -397.491712) (xy 454.262744 -397.491712) (xy 454.262744 -399.549112)
					(xy 452.408544 -399.549112) (xy 452.408544 -399.308066) (xy 452.166228 -399.308066) (xy 452.166228 -399.78965)
					(xy 456.710796 -399.78965) (xy 456.710796 -399.604738) (xy 454.554082 -399.604738) (xy 454.554082 -397.445738)
					(xy 456.710796 -397.445738) (xy 456.710796 -397.196056) (xy 453.259952 -397.196056) (xy 453.259952 -396.496032)
				)
			)
		)
	)
	(footprint ""
		(layer "F.Cu")
		(at 126.659894 -160.33496 -90)
		(property "Reference" "PC318_8"
			(at 0 0 270)
			(layer "F.SilkS")
			(hide yes)
			(effects
				(font
					(size 1.27 1.27)
				)
			)
		)
		(property "Value" ""
			(at 0 0 270)
			(layer "F.Fab")
			(effects
				(font
					(size 1.27 1.27)
				)
			)
		)
		(duplicate_pad_numbers_are_jumpers no)
		(fp_line
			(start -0.7874 0.4064)
			(end -0.7874 -0.4064)
			(stroke
				(width 0.1524)
				(type default)
			)
			(layer "F.SilkS")
		)
		(fp_line
			(start 0.7874 0.4064)
			(end -0.7874 0.4064)
			(stroke
				(width 0.1524)
				(type default)
			)
			(layer "F.SilkS")
		)
		(fp_line
			(start -0.7874 -0.4064)
			(end 0.7874 -0.4064)
			(stroke
				(width 0.1524)
				(type default)
			)
			(layer "F.SilkS")
		)
		(fp_line
			(start 0.7874 -0.4064)
			(end 0.7874 0.4064)
			(stroke
				(width 0.1524)
				(type default)
			)
			(layer "F.SilkS")
		)
		(fp_line
			(start -0.67945 0.3048)
			(end -0.67945 -0.305054)
			(stroke
				(width 0.1)
				(type default)
			)
			(layer "F.Fab")
		)
		(fp_line
			(start -0.12065 0.3048)
			(end -0.67945 0.3048)
			(stroke
				(width 0.1)
				(type default)
			)
			(layer "F.Fab")
		)
		(fp_line
			(start 0.120396 0.3048)
			(end 0.120396 0.2794)
			(stroke
				(width 0.1)
				(type default)
			)
			(layer "F.Fab")
		)
		(fp_line
			(start 0.67945 0.3048)
			(end 0.120396 0.3048)
			(stroke
				(width 0.1)
				(type default)
			)
			(layer "F.Fab")
		)
		(fp_line
			(start -0.12065 0.2794)
			(end -0.12065 0.3048)
			(stroke
				(width 0.1)
				(type default)
			)
			(layer "F.Fab")
		)
		(fp_line
			(start 0.120396 0.2794)
			(end -0.12065 0.2794)
			(stroke
				(width 0.1)
				(type default)
			)
			(layer "F.Fab")
		)
		(fp_line
			(start -0.12065 -0.2794)
			(end 0.12065 -0.2794)
			(stroke
				(width 0.1)
				(type default)
			)
			(layer "F.Fab")
		)
		(fp_line
			(start 0.12065 -0.2794)
			(end 0.12065 -0.3048)
			(stroke
				(width 0.1)
				(type default)
			)
			(layer "F.Fab")
		)
		(fp_line
			(start 0.12065 -0.3048)
			(end 0.67945 -0.3048)
			(stroke
				(width 0.1)
				(type default)
			)
			(layer "F.Fab")
		)
		(fp_line
			(start 0.67945 -0.3048)
			(end 0.67945 0.3048)
			(stroke
				(width 0.1)
				(type default)
			)
			(layer "F.Fab")
		)
		(fp_line
			(start -0.67945 -0.305054)
			(end -0.12065 -0.305054)
			(stroke
				(width 0.1)
				(type default)
			)
			(layer "F.Fab")
		)
		(fp_line
			(start -0.12065 -0.305054)
			(end -0.12065 -0.2794)
			(stroke
				(width 0.1)
				(type default)
			)
			(layer "F.Fab")
		)
		(pad "1" smd circle
			(at -0.40005 0 270)
			(size 0 0)
			(layers "F.Cu" "F.Mask" "F.Paste")
			(net "PVDDCR_CPU0_P1_VCCS")
		)
		(pad "2" smd circle
			(at 0.40005 0 270)
			(size 0 0)
			(layers "F.Cu" "F.Mask" "F.Paste")
			(net "GND")
		)
	)
	(footprint ""
		(layer "F.Cu")
		(at 239.53597 -292.988238 180)
		(property "Reference" "PR6502"
			(at 0 0 180)
			(layer "F.SilkS")
			(hide yes)
			(effects
				(font
					(size 1.27 1.27)
				)
			)
		)
		(property "Value" ""
			(at 0 0 180)
			(layer "F.Fab")
			(effects
				(font
					(size 1.27 1.27)
				)
			)
		)
		(duplicate_pad_numbers_are_jumpers no)
		(fp_line
			(start 0.7874 0.4064)
			(end -0.7874 0.4064)
			(stroke
				(width 0.1524)
				(type default)
			)
			(layer "F.SilkS")
		)
		(fp_line
			(start 0.7874 -0.4064)
			(end 0.7874 0.4064)
			(stroke
				(width 0.1524)
				(type default)
			)
			(layer "F.SilkS")
		)
		(fp_line
			(start -0.7874 0.4064)
			(end -0.7874 -0.4064)
			(stroke
				(width 0.1524)
				(type default)
			)
			(layer "F.SilkS")
		)
		(fp_line
			(start -0.7874 -0.4064)
			(end 0.7874 -0.4064)
			(stroke
				(width 0.1524)
				(type default)
			)
			(layer "F.SilkS")
		)
		(fp_line
			(start 0.67945 0.3048)
			(end 0.120396 0.3048)
			(stroke
				(width 0.1)
				(type default)
			)
			(layer "F.Fab")
		)
		(fp_line
			(start 0.67945 -0.3048)
			(end 0.67945 0.3048)
			(stroke
				(width 0.1)
				(type default)
			)
			(layer "F.Fab")
		)
		(fp_line
			(start 0.12065 -0.2794)
			(end 0.12065 -0.3048)
			(stroke
				(width 0.1)
				(type default)
			)
			(layer "F.Fab")
		)
		(fp_line
			(start 0.12065 -0.3048)
			(end 0.67945 -0.3048)
			(stroke
				(width 0.1)
				(type default)
			)
			(layer "F.Fab")
		)
		(fp_line
			(start 0.120396 0.3048)
			(end 0.120396 0.2794)
			(stroke
				(width 0.1)
				(type default)
			)
			(layer "F.Fab")
		)
		(fp_line
			(start 0.120396 0.2794)
			(end -0.12065 0.2794)
			(stroke
				(width 0.1)
				(type default)
			)
			(layer "F.Fab")
		)
		(fp_line
			(start -0.12065 0.3048)
			(end -0.67945 0.3048)
			(stroke
				(width 0.1)
				(type default)
			)
			(layer "F.Fab")
		)
		(fp_line
			(start -0.12065 0.2794)
			(end -0.12065 0.3048)
			(stroke
				(width 0.1)
				(type default)
			)
			(layer "F.Fab")
		)
		(fp_line
			(start -0.12065 -0.2794)
			(end 0.12065 -0.2794)
			(stroke
				(width 0.1)
				(type default)
			)
			(layer "F.Fab")
		)
		(fp_line
			(start -0.12065 -0.305054)
			(end -0.12065 -0.2794)
			(stroke
				(width 0.1)
				(type default)
			)
			(layer "F.Fab")
		)
		(fp_line
			(start -0.67945 0.3048)
			(end -0.67945 -0.305054)
			(stroke
				(width 0.1)
				(type default)
			)
			(layer "F.Fab")
		)
		(fp_line
			(start -0.67945 -0.305054)
			(end -0.12065 -0.305054)
			(stroke
				(width 0.1)
				(type default)
			)
			(layer "F.Fab")
		)
		(pad "1" smd circle
			(at -0.40005 0 180)
			(size 0 0)
			(layers "F.Cu" "F.Mask" "F.Paste")
			(net "P1V8_RETIMER_CPU0_CS")
		)
		(pad "2" smd circle
			(at 0.40005 0 180)
			(size 0 0)
			(layers "F.Cu" "F.Mask" "F.Paste")
			(net "GND")
		)
	)
	(footprint ""
		(layer "F.Cu")
		(at 339.663278 -172.40631)
		(property "Reference" "TP7"
			(at -3.053842 0 0)
			(unlocked yes)
			(layer "F.SilkS")
			(effects
				(font
					(size 0.7874 0.5842)
					(thickness 0.1524)
				)
				(justify left)
			)
		)
		(property "Value" ""
			(at 0 0 0)
			(layer "F.Fab")
			(effects
				(font
					(size 1.27 1.27)
				)
			)
		)
		(duplicate_pad_numbers_are_jumpers no)
		(pad "1" smd circle
			(at 0 0)
			(size 0.762 0.762)
			(layers "F.Cu" "F.Mask" "F.Paste")
			(net "VSENSE_PVDDCR_CPU0_P0_DP")
		)
	)
	(footprint ""
		(layer "F.Cu")
		(at 148.73859 -95.517208 90)
		(property "Reference" "R3306"
			(at 0 0 90)
			(layer "F.SilkS")
			(hide yes)
			(effects
				(font
					(size 1.27 1.27)
				)
			)
		)
		(property "Value" ""
			(at 0 0 90)
			(layer "F.Fab")
			(effects
				(font
					(size 1.27 1.27)
				)
			)
		)
		(duplicate_pad_numbers_are_jumpers no)
		(fp_line
			(start 0.7874 -0.4064)
			(end 0.7874 0.4064)
			(stroke
				(width 0.1524)
				(type default)
			)
			(layer "F.SilkS")
		)
		(fp_line
			(start -0.7874 -0.4064)
			(end 0.7874 -0.4064)
			(stroke
				(width 0.1524)
				(type default)
			)
			(layer "F.SilkS")
		)
		(fp_line
			(start 0.7874 0.4064)
			(end -0.7874 0.4064)
			(stroke
				(width 0.1524)
				(type default)
			)
			(layer "F.SilkS")
		)
		(fp_line
			(start -0.7874 0.4064)
			(end -0.7874 -0.4064)
			(stroke
				(width 0.1524)
				(type default)
			)
			(layer "F.SilkS")
		)
		(fp_line
			(start -0.12065 -0.305054)
			(end -0.12065 -0.2794)
			(stroke
				(width 0.1)
				(type default)
			)
			(layer "F.Fab")
		)
		(fp_line
			(start -0.67945 -0.305054)
			(end -0.12065 -0.305054)
			(stroke
				(width 0.1)
				(type default)
			)
			(layer "F.Fab")
		)
		(fp_line
			(start 0.67945 -0.3048)
			(end 0.67945 0.3048)
			(stroke
				(width 0.1)
				(type default)
			)
			(layer "F.Fab")
		)
		(fp_line
			(start 0.12065 -0.3048)
			(end 0.67945 -0.3048)
			(stroke
				(width 0.1)
				(type default)
			)
			(layer "F.Fab")
		)
		(fp_line
			(start 0.12065 -0.2794)
			(end 0.12065 -0.3048)
			(stroke
				(width 0.1)
				(type default)
			)
			(layer "F.Fab")
		)
		(fp_line
			(start -0.12065 -0.2794)
			(end 0.12065 -0.2794)
			(stroke
				(width 0.1)
				(type default)
			)
			(layer "F.Fab")
		)
		(fp_line
			(start 0.120396 0.2794)
			(end -0.12065 0.2794)
			(stroke
				(width 0.1)
				(type default)
			)
			(layer "F.Fab")
		)
		(fp_line
			(start -0.12065 0.2794)
			(end -0.12065 0.3048)
			(stroke
				(width 0.1)
				(type default)
			)
			(layer "F.Fab")
		)
		(fp_line
			(start 0.67945 0.3048)
			(end 0.120396 0.3048)
			(stroke
				(width 0.1)
				(type default)
			)
			(layer "F.Fab")
		)
		(fp_line
			(start 0.120396 0.3048)
			(end 0.120396 0.2794)
			(stroke
				(width 0.1)
				(type default)
			)
			(layer "F.Fab")
		)
		(fp_line
			(start -0.12065 0.3048)
			(end -0.67945 0.3048)
			(stroke
				(width 0.1)
				(type default)
			)
			(layer "F.Fab")
		)
		(fp_line
			(start -0.67945 0.3048)
			(end -0.67945 -0.305054)
			(stroke
				(width 0.1)
				(type default)
			)
			(layer "F.Fab")
		)
		(pad "1" smd circle
			(at -0.40005 0 90)
			(size 0 0)
			(layers "F.Cu" "F.Mask" "F.Paste")
			(net "OCP_V3_2_PRSNT_ALL_R_N")
		)
		(pad "2" smd circle
			(at 0.40005 0 90)
			(size 0 0)
			(layers "F.Cu" "F.Mask" "F.Paste")
			(net "OCP_V3_2_PRSNT_ALL_R3_N")
		)
	)
	(footprint ""
		(layer "F.Cu")
		(at 180.528468 -47.139098)
		(property "Reference" "C9102"
			(at 0 0 0)
			(layer "F.SilkS")
			(hide yes)
			(effects
				(font
					(size 1.27 1.27)
				)
			)
		)
		(property "Value" ""
			(at 0 0 0)
			(layer "F.Fab")
			(effects
				(font
					(size 1.27 1.27)
				)
			)
		)
		(duplicate_pad_numbers_are_jumpers no)
		(fp_line
			(start -0.299974 -0.150114)
			(end 0.299974 -0.150114)
			(stroke
				(width 0.1)
				(type default)
			)
			(layer "F.Fab")
		)
		(fp_line
			(start -0.299974 0.150114)
			(end -0.299974 -0.150114)
			(stroke
				(width 0.1)
				(type default)
			)
			(layer "F.Fab")
		)
		(fp_line
			(start 0.299974 -0.150114)
			(end 0.299974 0.150114)
			(stroke
				(width 0.1)
				(type default)
			)
			(layer "F.Fab")
		)
		(fp_line
			(start 0.299974 0.150114)
			(end -0.299974 0.150114)
			(stroke
				(width 0.1)
				(type default)
			)
			(layer "F.Fab")
		)
		(pad "1" smd rect
			(at -0.2667 0)
			(size 0.3048 0.381)
			(layers "F.Cu" "F.Mask" "F.Paste")
			(net "P3E_CPU1_P4_TX_C_DP<1>")
		)
		(pad "2" smd rect
			(at 0.2667 0)
			(size 0.3048 0.381)
			(layers "F.Cu" "F.Mask" "F.Paste")
			(net "P3E_CPU1_P4_TX_DP<1>")
		)
	)
)
